FILE_TYPE = CONNECTIVITY;
{Allegro Design Entry HDL 17.2-2016 S081 (4005846) 1/11/2022}
"PAGE_NUMBER" = 73;
0"NC";
1"GND\g";
2"PVDDCR_SOC_P1\g";
3"GND\g";
4"PVDDCR_SOC_P1\g";
5"GND\g";
6"PVDDCR_SOC_P1\g";
7"GND\g";
8"PVDDCR_SOC_P1\g";
9"GND\g";
10"PVDDCR_SOC_P1\g";
11"PVDDCR_SOC_P1\g";
12"GND\g";
13"GND\g";
14"PVDDCR_SOC_P1\g";
15"GND\g";
16"PVDDCR_SOC_P1\g";
17"GND\g";
18"PVDD11_S3_P1\g";
19"GND\g";
20"PVDD11_S3_P1\g";
21"GND\g";
22"PVDD11_S3_P1\g";
23"GND\g";
24"PVDD11_S3_P1\g";
25"GND\g";
26"PVDD11_S3_P1\g";
27"GND\g";
28"PVDDIO_P1\g";
29"GND\g";
30"PVDDIO_P1\g";
31"GND\g";
32"PVDDIO_P1\g";
%"Q_CAP"
"1","(400,1075)","0","pure_quanta","I1";
;
LOCATION"C3912"
$SEC"1"
CDS_SEC"1"
MATERIAL"X6S"
TOLERANCE"20%"
VALUE"22UF"
PART_NUMBER"CH622KMEB02"
VOLTAGE"4V"
PACK_TYPE"C0402"
CDS_LIB"pure_quanta";
"B"
$PN"2"1;
"A"
$PN"1"4;
%"UNIVERSAL_POWER"
"1","(400,2075)","0","pure_quanta_power","I10";
;
HDL_POWER"PVDDCR_SOC_P1"
CDS_LIB"pure_quanta_power";
"A"2;
%"Q_CAP"
"1","(5450,2650)","0","pure_quanta","I100";
;
LOCATION"C2486"
$SEC"1"
CDS_SEC"1"
MATERIAL"X6S"
TOLERANCE"20%"
VALUE"22UF"
PART_NUMBER"CH622KMEB02"
VOLTAGE"4V"
PACK_TYPE"C0402"
CDS_LIB"pure_quanta";
"B"
$PN"2"25;
"A"
$PN"1"24;
%"Q_CAP"
"1","(5900,2025)","0","pure_quanta","I101";
;
LOCATION"C2491"
$SEC"1"
CDS_SEC"1"
MATERIAL"X6S"
TOLERANCE"20%"
VALUE"22UF"
PART_NUMBER"CH622KMEB02"
VOLTAGE"4V"
PACK_TYPE"C0402"
CDS_LIB"pure_quanta";
"B"
$PN"2"17;
"A"
$PN"1"26;
%"Q_CAP"
"1","(5900,2650)","0","pure_quanta","I102";
;
LOCATION"C2490"
$SEC"1"
CDS_SEC"1"
MATERIAL"X6S"
TOLERANCE"20%"
VALUE"22UF"
PART_NUMBER"CH622KMEB02"
VOLTAGE"4V"
PACK_TYPE"C0402"
CDS_LIB"pure_quanta";
"B"
$PN"2"25;
"A"
$PN"1"24;
%"Q_CAP"
"1","(5450,3325)","0","pure_quanta","I103";
;
LOCATION"C2485"
$SEC"1"
CDS_SEC"1"
MATERIAL"X6S"
TOLERANCE"20%"
VALUE"22UF"
PART_NUMBER"CH622KMEB02"
VOLTAGE"4V"
PACK_TYPE"C0402"
CDS_LIB"pure_quanta";
"B"
$PN"2"23;
"A"
$PN"1"22;
%"Q_CAP"
"1","(5900,3325)","0","pure_quanta","I104";
;
LOCATION"C2489"
$SEC"1"
CDS_SEC"1"
MATERIAL"X6S"
TOLERANCE"20%"
VALUE"22UF"
PART_NUMBER"CH622KMEB02"
VOLTAGE"4V"
PACK_TYPE"C0402"
CDS_LIB"pure_quanta";
"B"
$PN"2"23;
"A"
$PN"1"22;
%"Q_CAP"
"1","(6350,1375)","0","pure_quanta","I105";
;
LOCATION"C2497"
$SEC"1"
CDS_SEC"1"
MATERIAL"X6S"
TOLERANCE"20%"
VALUE"22UF"
PART_NUMBER"CH622KMEB02"
VOLTAGE"4V"
PACK_TYPE"C0402"
CDS_LIB"pure_quanta";
"B"
$PN"2"19;
"A"
$PN"1"18;
%"Q_CAP"
"1","(6800,1375)","0","pure_quanta","I106";
;
LOCATION"C2502"
$SEC"1"
CDS_SEC"1"
MATERIAL"X6S"
TOLERANCE"20%"
VALUE"22UF"
PART_NUMBER"CH622KMEB02"
VOLTAGE"4V"
PACK_TYPE"C0402"
CDS_LIB"pure_quanta";
"B"
$PN"2"19;
"A"
$PN"1"18;
%"Q_CAP"
"1","(7250,1375)","0","pure_quanta","I107";
;
LOCATION"C2506"
$SEC"1"
CDS_SEC"1"
MATERIAL"X6S"
TOLERANCE"20%"
VALUE"22UF"
PART_NUMBER"CH622KMEB02"
VOLTAGE"4V"
PACK_TYPE"C0402"
CDS_LIB"pure_quanta";
"B"
$PN"2"19;
"A"
$PN"1"18;
%"Q_CAP"
"1","(7700,1375)","0","pure_quanta","I108";
;
LOCATION"C2115"
$SEC"1"
CDS_SEC"1"
MATERIAL"X6S"
TOLERANCE"20%"
VALUE"22UF"
PART_NUMBER"CH622KMEB02"
VOLTAGE"4V"
PACK_TYPE"C0402"
CDS_LIB"pure_quanta";
"B"
$PN"2"19;
"A"
$PN"1"18;
%"Q_CAP"
"1","(8150,1375)","0","pure_quanta","I109";
;
LOCATION"C2121"
$SEC"1"
CDS_SEC"1"
MATERIAL"X6S"
TOLERANCE"20%"
VALUE"22UF"
PART_NUMBER"CH622KMEB02"
VOLTAGE"4V"
PACK_TYPE"C0402"
CDS_LIB"pure_quanta";
"B"
$PN"2"19;
"A"
$PN"1"18;
%"Q_CAP"
"1","(400,2475)","0","pure_quanta","I11";
;
LOCATION"C2412"
$SEC"1"
CDS_SEC"1"
MATERIAL"X6S"
TOLERANCE"20%"
VALUE"22UF"
PART_NUMBER"CH622KMEB02"
VOLTAGE"4V"
PACK_TYPE"C0402"
CDS_LIB"pure_quanta";
"B"
$PN"2"7;
"A"
$PN"1"6;
%"Q_CAP"
"1","(6350,2025)","0","pure_quanta","I110";
;
LOCATION"C2496"
$SEC"1"
CDS_SEC"1"
MATERIAL"X6S"
TOLERANCE"20%"
VALUE"22UF"
PART_NUMBER"CH622KMEB02"
VOLTAGE"4V"
PACK_TYPE"C0402"
CDS_LIB"pure_quanta";
"B"
$PN"2"17;
"A"
$PN"1"26;
%"Q_CAP"
"1","(6350,2650)","0","pure_quanta","I111";
;
LOCATION"C2495"
$SEC"1"
CDS_SEC"1"
MATERIAL"X6S"
TOLERANCE"20%"
VALUE"22UF"
PART_NUMBER"CH622KMEB02"
VOLTAGE"4V"
PACK_TYPE"C0402"
CDS_LIB"pure_quanta";
"B"
$PN"2"25;
"A"
$PN"1"24;
%"Q_CAP"
"1","(6800,2025)","0","pure_quanta","I112";
;
LOCATION"C2501"
$SEC"1"
CDS_SEC"1"
MATERIAL"X6S"
TOLERANCE"20%"
VALUE"22UF"
PART_NUMBER"CH622KMEB02"
VOLTAGE"4V"
PACK_TYPE"C0402"
CDS_LIB"pure_quanta";
"B"
$PN"2"17;
"A"
$PN"1"26;
%"Q_CAP"
"1","(6800,2650)","0","pure_quanta","I113";
;
LOCATION"C2500"
$SEC"1"
CDS_SEC"1"
MATERIAL"X6S"
TOLERANCE"20%"
VALUE"22UF"
PART_NUMBER"CH622KMEB02"
VOLTAGE"4V"
PACK_TYPE"C0402"
CDS_LIB"pure_quanta";
"B"
$PN"2"25;
"A"
$PN"1"24;
%"Q_CAP"
"1","(6350,3325)","0","pure_quanta","I114";
;
LOCATION"C2494"
$SEC"1"
CDS_SEC"1"
MATERIAL"X6S"
TOLERANCE"20%"
VALUE"22UF"
PART_NUMBER"CH622KMEB02"
VOLTAGE"4V"
PACK_TYPE"C0402"
CDS_LIB"pure_quanta";
"B"
$PN"2"23;
"A"
$PN"1"22;
%"UNIVERSAL_GND"
"1","(6350,3925)","0","pure_quanta_power","I115";
;
CDS_LIB"pure_quanta_power"
HDL_POWER"GND";
"A"27;
%"Q_CAP"
"1","(6800,3325)","0","pure_quanta","I116";
;
LOCATION"C2499"
$SEC"1"
CDS_SEC"1"
MATERIAL"X6S"
TOLERANCE"20%"
VALUE"22UF"
PART_NUMBER"CH622KMEB02"
VOLTAGE"4V"
PACK_TYPE"C0402"
CDS_LIB"pure_quanta";
"B"
$PN"2"23;
"A"
$PN"1"22;
%"Q_CAP"
"1","(7250,2025)","0","pure_quanta","I117";
;
LOCATION"C2505"
$SEC"1"
CDS_SEC"1"
MATERIAL"X6S"
TOLERANCE"20%"
VALUE"22UF"
PART_NUMBER"CH622KMEB02"
VOLTAGE"4V"
PACK_TYPE"C0402"
CDS_LIB"pure_quanta";
"B"
$PN"2"17;
"A"
$PN"1"26;
%"Q_CAP"
"1","(7250,2650)","0","pure_quanta","I118";
;
LOCATION"C2504"
$SEC"1"
CDS_SEC"1"
MATERIAL"X6S"
TOLERANCE"20%"
VALUE"22UF"
PART_NUMBER"CH622KMEB02"
VOLTAGE"4V"
PACK_TYPE"C0402"
CDS_LIB"pure_quanta";
"B"
$PN"2"25;
"A"
$PN"1"24;
%"Q_CAP"
"1","(7700,2650)","0","pure_quanta","I119";
;
LOCATION"C2113"
$SEC"1"
CDS_SEC"1"
MATERIAL"X6S"
TOLERANCE"20%"
VALUE"22UF"
PART_NUMBER"CH622KMEB02"
VOLTAGE"4V"
PACK_TYPE"C0402"
CDS_LIB"pure_quanta";
"B"
$PN"2"25;
"A"
$PN"1"24;
%"UNIVERSAL_POWER"
"1","(400,2750)","0","pure_quanta_power","I12";
;
HDL_POWER"PVDDCR_SOC_P1"
CDS_LIB"pure_quanta_power";
"A"6;
%"Q_CAP"
"1","(7700,2025)","0","pure_quanta","I120";
;
LOCATION"C2114"
$SEC"1"
CDS_SEC"1"
MATERIAL"X6S"
TOLERANCE"20%"
VALUE"22UF"
PART_NUMBER"CH622KMEB02"
VOLTAGE"4V"
PACK_TYPE"C0402"
CDS_LIB"pure_quanta";
"B"
$PN"2"17;
"A"
$PN"1"26;
%"Q_CAP"
"1","(8150,2025)","0","pure_quanta","I121";
;
LOCATION"C2120"
$SEC"1"
CDS_SEC"1"
MATERIAL"X6S"
TOLERANCE"20%"
VALUE"22UF"
PART_NUMBER"CH622KMEB02"
VOLTAGE"4V"
PACK_TYPE"C0402"
CDS_LIB"pure_quanta";
"B"
$PN"2"17;
"A"
$PN"1"26;
%"Q_CAP"
"1","(8150,2650)","0","pure_quanta","I122";
;
LOCATION"C2119"
$SEC"1"
CDS_SEC"1"
MATERIAL"X6S"
TOLERANCE"20%"
VALUE"22UF"
PART_NUMBER"CH622KMEB02"
VOLTAGE"4V"
PACK_TYPE"C0402"
CDS_LIB"pure_quanta";
"B"
$PN"2"25;
"A"
$PN"1"24;
%"Q_CAP"
"1","(7250,3325)","0","pure_quanta","I123";
;
LOCATION"C2503"
$SEC"1"
CDS_SEC"1"
MATERIAL"X6S"
TOLERANCE"20%"
VALUE"22UF"
PART_NUMBER"CH622KMEB02"
VOLTAGE"4V"
PACK_TYPE"C0402"
CDS_LIB"pure_quanta";
"B"
$PN"2"23;
"A"
$PN"1"22;
%"Q_CAP"
"1","(7700,3325)","0","pure_quanta","I124";
;
LOCATION"C2508"
$SEC"1"
CDS_SEC"1"
MATERIAL"X6S"
TOLERANCE"20%"
VALUE"22UF"
PART_NUMBER"CH622KMEB02"
VOLTAGE"4V"
PACK_TYPE"C0402"
CDS_LIB"pure_quanta";
"B"
$PN"2"23;
"A"
$PN"1"22;
%"Q_CAP"
"1","(8150,3325)","0","pure_quanta","I125";
;
LOCATION"C2118"
$SEC"1"
CDS_SEC"1"
MATERIAL"X6S"
TOLERANCE"20%"
VALUE"22UF"
PART_NUMBER"CH622KMEB02"
VOLTAGE"4V"
PACK_TYPE"C0402"
CDS_LIB"pure_quanta";
"B"
$PN"2"23;
"A"
$PN"1"22;
%"UNIVERSAL_GND"
"1","(4400,4175)","0","pure_quanta_power","I126";
;
CDS_LIB"pure_quanta_power"
HDL_POWER"GND";
"A"12;
%"Q_CAP"
"1","(4400,4550)","0","pure_quanta","I127";
;
LOCATION"C2472"
$SEC"1"
CDS_SEC"1"
MATERIAL"X6S"
TOLERANCE"20%"
VALUE"22UF"
PART_NUMBER"CH622KMEB02"
VOLTAGE"4V"
PACK_TYPE"C0402"
CDS_LIB"pure_quanta";
"B"
$PN"2"12;
"A"
$PN"1"11;
%"UNIVERSAL_GND"
"1","(4400,4850)","0","pure_quanta_power","I128";
;
CDS_LIB"pure_quanta_power"
HDL_POWER"GND";
"A"13;
%"Q_CAP"
"1","(5000,4300)","0","pure_quanta","I129";
;
LOCATION"C2479"
$SEC"1"
CDS_SEC"1"
MATERIAL"X6S"
TOLERANCE"20%"
VALUE"22UF"
PART_NUMBER"CH622KMEB02"
VOLTAGE"4V"
PACK_TYPE"C0402"
CDS_LIB"pure_quanta";
"B"
$PN"2"27;
"A"
$PN"1"32;
%"Q_CAP"
"1","(850,2475)","0","pure_quanta","I13";
;
LOCATION"C2419"
$SEC"1"
CDS_SEC"1"
MATERIAL"X6S"
TOLERANCE"20%"
VALUE"22UF"
PART_NUMBER"CH622KMEB02"
VOLTAGE"4V"
PACK_TYPE"C0402"
CDS_LIB"pure_quanta";
"B"
$PN"2"7;
"A"
$PN"1"6;
%"UNIVERSAL_POWER"
"1","(5000,4575)","0","pure_quanta_power","I130";
;
HDL_POWER"PVDDIO_P1"
CDS_LIB"pure_quanta_power";
"A"32;
%"Q_CAP"
"1","(4400,5225)","0","pure_quanta","I131";
;
LOCATION"C2471"
$SEC"1"
CDS_SEC"1"
MATERIAL"X6S"
TOLERANCE"20%"
VALUE"22UF"
PART_NUMBER"CH622KMEB02"
VOLTAGE"4V"
PACK_TYPE"C0402"
CDS_LIB"pure_quanta";
"B"
$PN"2"13;
"A"
$PN"1"16;
%"UNIVERSAL_GND"
"1","(4400,5500)","0","pure_quanta_power","I132";
;
CDS_LIB"pure_quanta_power"
HDL_POWER"GND";
"A"15;
%"Q_CAP"
"1","(4400,5875)","0","pure_quanta","I133";
;
LOCATION"C2470"
$SEC"1"
CDS_SEC"1"
MATERIAL"X6S"
TOLERANCE"20%"
VALUE"22UF"
PART_NUMBER"CH622KMEB02"
VOLTAGE"4V"
PACK_TYPE"C0402"
CDS_LIB"pure_quanta";
"B"
$PN"2"15;
"A"
$PN"1"14;
%"Q_CAP"
"1","(4975,5075)","0","pure_quanta","I134";
;
LOCATION"C2478"
$SEC"1"
CDS_SEC"1"
MATERIAL"X6S"
TOLERANCE"20%"
VALUE"22UF"
PART_NUMBER"CH622KMEB02"
VOLTAGE"4V"
PACK_TYPE"C0402"
CDS_LIB"pure_quanta";
"B"
$PN"2"31;
"A"
$PN"1"30;
%"UNIVERSAL_POWER"
"1","(4975,5350)","0","pure_quanta_power","I135";
;
HDL_POWER"PVDDIO_P1"
CDS_LIB"pure_quanta_power";
"A"30;
%"Q_CAP"
"1","(4975,5875)","0","pure_quanta","I136";
;
LOCATION"C2477"
$SEC"1"
CDS_SEC"1"
MATERIAL"X6S"
TOLERANCE"20%"
VALUE"22UF"
PART_NUMBER"CH622KMEB02"
VOLTAGE"4V"
PACK_TYPE"C0402"
CDS_LIB"pure_quanta";
"B"
$PN"2"29;
"A"
$PN"1"28;
%"Q_CAP"
"1","(5450,4300)","0","pure_quanta","I137";
;
LOCATION"C2103"
$SEC"1"
CDS_SEC"1"
MATERIAL"X6S"
TOLERANCE"20%"
VALUE"22UF"
PART_NUMBER"CH622KMEB02"
VOLTAGE"4V"
PACK_TYPE"C0402"
CDS_LIB"pure_quanta";
"B"
$PN"2"27;
"A"
$PN"1"32;
%"Q_CAP"
"1","(5900,4300)","0","pure_quanta","I138";
;
LOCATION"C2106"
$SEC"1"
CDS_SEC"1"
MATERIAL"X6S"
TOLERANCE"20%"
VALUE"22UF"
PART_NUMBER"CH622KMEB02"
VOLTAGE"4V"
PACK_TYPE"C0402"
CDS_LIB"pure_quanta";
"B"
$PN"2"27;
"A"
$PN"1"32;
%"Q_CAP"
"1","(5425,5075)","0","pure_quanta","I139";
;
LOCATION"C2484"
$SEC"1"
CDS_SEC"1"
MATERIAL"X6S"
TOLERANCE"20%"
VALUE"22UF"
PART_NUMBER"CH622KMEB02"
VOLTAGE"4V"
PACK_TYPE"C0402"
CDS_LIB"pure_quanta";
"B"
$PN"2"31;
"A"
$PN"1"30;
%"Q_CAP"
"1","(400,3150)","0","pure_quanta","I14";
;
LOCATION"C2411"
$SEC"1"
CDS_SEC"1"
MATERIAL"X6S"
TOLERANCE"20%"
VALUE"22UF"
PART_NUMBER"CH622KMEB02"
VOLTAGE"4V"
PACK_TYPE"C0402"
CDS_LIB"pure_quanta";
"B"
$PN"2"5;
"A"
$PN"1"10;
%"Q_CAP"
"1","(5425,5875)","0","pure_quanta","I140";
;
LOCATION"C2102"
$SEC"1"
CDS_SEC"1"
MATERIAL"X6S"
TOLERANCE"20%"
VALUE"22UF"
PART_NUMBER"CH622KMEB02"
VOLTAGE"4V"
PACK_TYPE"C0402"
CDS_LIB"pure_quanta";
"B"
$PN"2"29;
"A"
$PN"1"28;
%"Q_CAP"
"1","(5875,5075)","0","pure_quanta","I141";
;
LOCATION"C2105"
$SEC"1"
CDS_SEC"1"
MATERIAL"X6S"
TOLERANCE"20%"
VALUE"22UF"
PART_NUMBER"CH622KMEB02"
VOLTAGE"4V"
PACK_TYPE"C0402"
CDS_LIB"pure_quanta";
"B"
$PN"2"31;
"A"
$PN"1"30;
%"Q_CAP"
"1","(5875,5875)","0","pure_quanta","I142";
;
LOCATION"C2104"
$SEC"1"
CDS_SEC"1"
MATERIAL"X6S"
TOLERANCE"20%"
VALUE"22UF"
PART_NUMBER"CH622KMEB02"
VOLTAGE"4V"
PACK_TYPE"C0402"
CDS_LIB"pure_quanta";
"B"
$PN"2"29;
"A"
$PN"1"28;
%"UNIVERSAL_POWER"
"1","(4975,6150)","0","pure_quanta_power","I143";
;
HDL_POWER"PVDDIO_P1"
CDS_LIB"pure_quanta_power";
"A"28;
%"Q_CAP"
"1","(6350,4300)","0","pure_quanta","I144";
;
LOCATION"C2108"
$SEC"1"
CDS_SEC"1"
MATERIAL"X6S"
TOLERANCE"20%"
VALUE"22UF"
PART_NUMBER"CH622KMEB02"
VOLTAGE"4V"
PACK_TYPE"C0402"
CDS_LIB"pure_quanta";
"B"
$PN"2"27;
"A"
$PN"1"32;
%"Q_CAP"
"1","(6325,5075)","0","pure_quanta","I145";
;
LOCATION"C2107"
$SEC"1"
CDS_SEC"1"
MATERIAL"X6S"
TOLERANCE"20%"
VALUE"22UF"
PART_NUMBER"CH622KMEB02"
VOLTAGE"4V"
PACK_TYPE"C0402"
CDS_LIB"pure_quanta";
"B"
$PN"2"31;
"A"
$PN"1"30;
%"Q_CAP"
"1","(6325,5875)","0","pure_quanta","I146";
;
LOCATION"C2493"
$SEC"1"
CDS_SEC"1"
MATERIAL"X6S"
TOLERANCE"20%"
VALUE"22UF"
PART_NUMBER"CH622KMEB02"
VOLTAGE"4V"
PACK_TYPE"C0402"
CDS_LIB"pure_quanta";
"B"
$PN"2"29;
"A"
$PN"1"28;
%"Q_CAP"
"1","(6775,5075)","0","pure_quanta","I147";
;
LOCATION"C2498"
$SEC"1"
CDS_SEC"1"
MATERIAL"X6S"
TOLERANCE"20%"
VALUE"22UF"
PART_NUMBER"CH622KMEB02"
VOLTAGE"4V"
PACK_TYPE"C0402"
CDS_LIB"pure_quanta";
"B"
$PN"2"31;
"A"
$PN"1"30;
%"Q_CAP"
"1","(6775,5875)","0","pure_quanta","I148";
;
LOCATION"C2109"
$SEC"1"
CDS_SEC"1"
MATERIAL"X6S"
TOLERANCE"20%"
VALUE"22UF"
PART_NUMBER"CH622KMEB02"
VOLTAGE"4V"
PACK_TYPE"C0402"
CDS_LIB"pure_quanta";
"B"
$PN"2"29;
"A"
$PN"1"28;
%"Q_CAP"
"1","(7225,5075)","0","pure_quanta","I149";
;
LOCATION"C2111"
$SEC"1"
CDS_SEC"1"
MATERIAL"X6S"
TOLERANCE"20%"
VALUE"22UF"
PART_NUMBER"CH622KMEB02"
VOLTAGE"4V"
PACK_TYPE"C0402"
CDS_LIB"pure_quanta";
"B"
$PN"2"31;
"A"
$PN"1"30;
%"UNIVERSAL_POWER"
"1","(400,3425)","0","pure_quanta_power","I15";
;
HDL_POWER"PVDDCR_SOC_P1"
CDS_LIB"pure_quanta_power";
"A"10;
%"Q_CAP"
"1","(7675,5075)","0","pure_quanta","I150";
;
LOCATION"C2112"
$SEC"1"
CDS_SEC"1"
MATERIAL"X6S"
TOLERANCE"20%"
VALUE"22UF"
PART_NUMBER"CH622KMEB02"
VOLTAGE"4V"
PACK_TYPE"C0402"
CDS_LIB"pure_quanta";
"B"
$PN"2"31;
"A"
$PN"1"30;
%"Q_CAP"
"1","(7225,5875)","0","pure_quanta","I151";
;
LOCATION"C2110"
$SEC"1"
CDS_SEC"1"
MATERIAL"X6S"
TOLERANCE"20%"
VALUE"22UF"
PART_NUMBER"CH622KMEB02"
VOLTAGE"4V"
PACK_TYPE"C0402"
CDS_LIB"pure_quanta";
"B"
$PN"2"29;
"A"
$PN"1"28;
%"Q_CAP"
"1","(7675,5875)","0","pure_quanta","I152";
;
LOCATION"C2507"
$SEC"1"
CDS_SEC"1"
MATERIAL"X6S"
TOLERANCE"20%"
VALUE"22UF"
PART_NUMBER"CH622KMEB02"
VOLTAGE"4V"
PACK_TYPE"C0402"
CDS_LIB"pure_quanta";
"B"
$PN"2"29;
"A"
$PN"1"28;
%"Q_CAP"
"1","(8125,5075)","0","pure_quanta","I153";
;
LOCATION"C2117"
$SEC"1"
CDS_SEC"1"
MATERIAL"X6S"
TOLERANCE"20%"
VALUE"22UF"
PART_NUMBER"CH622KMEB02"
VOLTAGE"4V"
PACK_TYPE"C0402"
CDS_LIB"pure_quanta";
"B"
$PN"2"31;
"A"
$PN"1"30;
%"Q_CAP"
"1","(8125,5875)","0","pure_quanta","I154";
;
LOCATION"C2116"
$SEC"1"
CDS_SEC"1"
MATERIAL"X6S"
TOLERANCE"20%"
VALUE"22UF"
PART_NUMBER"CH622KMEB02"
VOLTAGE"4V"
PACK_TYPE"C0402"
CDS_LIB"pure_quanta";
"B"
$PN"2"29;
"A"
$PN"1"28;
%"Q_CAP"
"1","(8600,1375)","0","pure_quanta","I155";
;
LOCATION"C3921"
$SEC"1"
CDS_SEC"1"
MATERIAL"X6S"
TOLERANCE"20%"
VALUE"22UF"
PART_NUMBER"CH622KMEB02"
VOLTAGE"4V"
PACK_TYPE"C0402"
CDS_LIB"pure_quanta";
"B"
$PN"2"19;
"A"
$PN"1"18;
%"UNIVERSAL_GND"
"1","(9000,1000)","0","pure_quanta_power","I156";
;
CDS_LIB"pure_quanta_power"
HDL_POWER"GND";
"A"19;
%"Q_CAP"
"1","(9000,1375)","0","pure_quanta","I157";
;
LOCATION"C3922"
$SEC"1"
CDS_SEC"1"
MATERIAL"X6S"
TOLERANCE"20%"
VALUE"22UF"
PART_NUMBER"CH622KMEB02"
VOLTAGE"4V"
PACK_TYPE"C0402"
CDS_LIB"pure_quanta";
"B"
$PN"2"19;
"A"
$PN"1"18;
%"UNIVERSAL_GND"
"1","(9000,1650)","0","pure_quanta_power","I158";
;
CDS_LIB"pure_quanta_power"
HDL_POWER"GND";
"A"17;
%"Q_CAP"
"1","(8600,2025)","0","pure_quanta","I159";
;
LOCATION"C2126"
$SEC"1"
CDS_SEC"1"
MATERIAL"X6S"
TOLERANCE"20%"
VALUE"22UF"
PART_NUMBER"CH622KMEB02"
VOLTAGE"4V"
PACK_TYPE"C0402"
CDS_LIB"pure_quanta";
"B"
$PN"2"17;
"A"
$PN"1"26;
%"Q_CAP"
"1","(400,3850)","0","pure_quanta","I16";
;
LOCATION"C2410"
$SEC"1"
CDS_SEC"1"
MATERIAL"X6S"
TOLERANCE"20%"
VALUE"22UF"
PART_NUMBER"CH622KMEB02"
VOLTAGE"4V"
PACK_TYPE"C0402"
CDS_LIB"pure_quanta";
"B"
$PN"2"9;
"A"
$PN"1"8;
%"Q_CAP"
"1","(8600,2650)","0","pure_quanta","I160";
;
LOCATION"C2125"
$SEC"1"
CDS_SEC"1"
MATERIAL"X6S"
TOLERANCE"20%"
VALUE"22UF"
PART_NUMBER"CH622KMEB02"
VOLTAGE"4V"
PACK_TYPE"C0402"
CDS_LIB"pure_quanta";
"B"
$PN"2"25;
"A"
$PN"1"24;
%"Q_CAP"
"1","(9000,2025)","0","pure_quanta","I161";
;
LOCATION"C2511"
$SEC"1"
CDS_SEC"1"
MATERIAL"X6S"
TOLERANCE"20%"
VALUE"22UF"
PART_NUMBER"CH622KMEB02"
VOLTAGE"4V"
PACK_TYPE"C0402"
CDS_LIB"pure_quanta";
"B"
$PN"2"17;
"A"
$PN"1"26;
%"UNIVERSAL_GND"
"1","(9000,2300)","0","pure_quanta_power","I162";
;
CDS_LIB"pure_quanta_power"
HDL_POWER"GND";
"A"25;
%"Q_CAP"
"1","(9000,2650)","0","pure_quanta","I163";
;
LOCATION"C2510"
$SEC"1"
CDS_SEC"1"
MATERIAL"X6S"
TOLERANCE"20%"
VALUE"22UF"
PART_NUMBER"CH622KMEB02"
VOLTAGE"4V"
PACK_TYPE"C0402"
CDS_LIB"pure_quanta";
"B"
$PN"2"25;
"A"
$PN"1"24;
%"Q_CAP"
"1","(8600,3325)","0","pure_quanta","I164";
;
LOCATION"C2124"
$SEC"1"
CDS_SEC"1"
MATERIAL"X6S"
TOLERANCE"20%"
VALUE"22UF"
PART_NUMBER"CH622KMEB02"
VOLTAGE"4V"
PACK_TYPE"C0402"
CDS_LIB"pure_quanta";
"B"
$PN"2"23;
"A"
$PN"1"22;
%"UNIVERSAL_GND"
"1","(9000,2950)","0","pure_quanta_power","I165";
;
CDS_LIB"pure_quanta_power"
HDL_POWER"GND";
"A"23;
%"Q_CAP"
"1","(9000,3325)","0","pure_quanta","I166";
;
LOCATION"C2128"
$SEC"1"
CDS_SEC"1"
MATERIAL"X6S"
TOLERANCE"20%"
VALUE"22UF"
PART_NUMBER"CH622KMEB02"
VOLTAGE"4V"
PACK_TYPE"C0402"
CDS_LIB"pure_quanta";
"B"
$PN"2"23;
"A"
$PN"1"22;
%"UNIVERSAL_GND"
"1","(8975,4700)","0","pure_quanta_power","I167";
;
CDS_LIB"pure_quanta_power"
HDL_POWER"GND";
"A"31;
%"Q_CAP"
"1","(8575,5075)","0","pure_quanta","I168";
;
LOCATION"C2123"
$SEC"1"
CDS_SEC"1"
MATERIAL"X6S"
TOLERANCE"20%"
VALUE"22UF"
PART_NUMBER"CH622KMEB02"
VOLTAGE"4V"
PACK_TYPE"C0402"
CDS_LIB"pure_quanta";
"B"
$PN"2"31;
"A"
$PN"1"30;
%"Q_CAP"
"1","(8575,5875)","0","pure_quanta","I169";
;
LOCATION"C2122"
$SEC"1"
CDS_SEC"1"
MATERIAL"X6S"
TOLERANCE"20%"
VALUE"22UF"
PART_NUMBER"CH622KMEB02"
VOLTAGE"4V"
PACK_TYPE"C0402"
CDS_LIB"pure_quanta";
"B"
$PN"2"29;
"A"
$PN"1"28;
%"Q_CAP"
"1","(850,3150)","0","pure_quanta","I17";
;
LOCATION"C2418"
$SEC"1"
CDS_SEC"1"
MATERIAL"X6S"
TOLERANCE"20%"
VALUE"22UF"
PART_NUMBER"CH622KMEB02"
VOLTAGE"4V"
PACK_TYPE"C0402"
CDS_LIB"pure_quanta";
"B"
$PN"2"5;
"A"
$PN"1"10;
%"Q_CAP"
"1","(8975,5075)","0","pure_quanta","I170";
;
LOCATION"C2509"
$SEC"1"
CDS_SEC"1"
MATERIAL"X6S"
TOLERANCE"20%"
VALUE"22UF"
PART_NUMBER"CH622KMEB02"
VOLTAGE"4V"
PACK_TYPE"C0402"
CDS_LIB"pure_quanta";
"B"
$PN"2"31;
"A"
$PN"1"30;
%"UNIVERSAL_GND"
"1","(8975,5500)","0","pure_quanta_power","I171";
;
CDS_LIB"pure_quanta_power"
HDL_POWER"GND";
"A"29;
%"Q_CAP"
"1","(8975,5875)","0","pure_quanta","I172";
;
LOCATION"C2127"
$SEC"1"
CDS_SEC"1"
MATERIAL"X6S"
TOLERANCE"20%"
VALUE"22UF"
PART_NUMBER"CH622KMEB02"
VOLTAGE"4V"
PACK_TYPE"C0402"
CDS_LIB"pure_quanta";
"B"
$PN"2"29;
"A"
$PN"1"28;
%"Q_CAP"
"1","(2650,5875)","0","pure_quanta","I173";
;
LOCATION"C2442"
$SEC"1"
CDS_SEC"1"
MATERIAL"X6S"
TOLERANCE"20%"
VALUE"22UF"
PART_NUMBER"CH622KMEB02"
VOLTAGE"4V"
PACK_TYPE"C0402"
CDS_LIB"pure_quanta";
"B"
$PN"2"15;
"A"
$PN"1"14;
%"Q_CAP"
"1","(2200,5875)","0","pure_quanta","I174";
;
LOCATION"C2435"
$SEC"1"
CDS_SEC"1"
MATERIAL"X6S"
TOLERANCE"20%"
VALUE"22UF"
PART_NUMBER"CH622KMEB02"
VOLTAGE"4V"
PACK_TYPE"C0402"
CDS_LIB"pure_quanta";
"B"
$PN"2"15;
"A"
$PN"1"14;
%"Q_CAP"
"1","(1750,5875)","0","pure_quanta","I175";
;
LOCATION"C2428"
$SEC"1"
CDS_SEC"1"
MATERIAL"X6S"
TOLERANCE"20%"
VALUE"22UF"
PART_NUMBER"CH622KMEB02"
VOLTAGE"4V"
PACK_TYPE"C0402"
CDS_LIB"pure_quanta";
"B"
$PN"2"15;
"A"
$PN"1"14;
%"Q_CAP"
"1","(850,3850)","0","pure_quanta","I18";
;
LOCATION"C2417"
$SEC"1"
CDS_SEC"1"
MATERIAL"X6S"
TOLERANCE"20%"
VALUE"22UF"
PART_NUMBER"CH622KMEB02"
VOLTAGE"4V"
PACK_TYPE"C0402"
CDS_LIB"pure_quanta";
"B"
$PN"2"9;
"A"
$PN"1"8;
%"Q_CAP"
"1","(1300,2475)","0","pure_quanta","I19";
;
LOCATION"C2426"
$SEC"1"
CDS_SEC"1"
MATERIAL"X6S"
TOLERANCE"20%"
VALUE"22UF"
PART_NUMBER"CH622KMEB02"
VOLTAGE"4V"
PACK_TYPE"C0402"
CDS_LIB"pure_quanta";
"B"
$PN"2"7;
"A"
$PN"1"6;
%"UNIVERSAL_POWER"
"1","(400,1350)","0","pure_quanta_power","I2";
;
HDL_POWER"PVDDCR_SOC_P1"
CDS_LIB"pure_quanta_power";
"A"4;
%"Q_CAP"
"1","(1750,2475)","0","pure_quanta","I20";
;
LOCATION"C2433"
$SEC"1"
CDS_SEC"1"
MATERIAL"X6S"
TOLERANCE"20%"
VALUE"22UF"
PART_NUMBER"CH622KMEB02"
VOLTAGE"4V"
PACK_TYPE"C0402"
CDS_LIB"pure_quanta";
"B"
$PN"2"7;
"A"
$PN"1"6;
%"Q_CAP"
"1","(1300,3150)","0","pure_quanta","I21";
;
LOCATION"C2425"
$SEC"1"
CDS_SEC"1"
MATERIAL"X6S"
TOLERANCE"20%"
VALUE"22UF"
PART_NUMBER"CH622KMEB02"
VOLTAGE"4V"
PACK_TYPE"C0402"
CDS_LIB"pure_quanta";
"B"
$PN"2"5;
"A"
$PN"1"10;
%"Q_CAP"
"1","(1300,3850)","0","pure_quanta","I22";
;
LOCATION"C2424"
$SEC"1"
CDS_SEC"1"
MATERIAL"X6S"
TOLERANCE"20%"
VALUE"22UF"
PART_NUMBER"CH622KMEB02"
VOLTAGE"4V"
PACK_TYPE"C0402"
CDS_LIB"pure_quanta";
"B"
$PN"2"9;
"A"
$PN"1"8;
%"Q_CAP"
"1","(1750,3150)","0","pure_quanta","I23";
;
LOCATION"C2432"
$SEC"1"
CDS_SEC"1"
MATERIAL"X6S"
TOLERANCE"20%"
VALUE"22UF"
PART_NUMBER"CH622KMEB02"
VOLTAGE"4V"
PACK_TYPE"C0402"
CDS_LIB"pure_quanta";
"B"
$PN"2"5;
"A"
$PN"1"10;
%"Q_CAP"
"1","(1750,3850)","0","pure_quanta","I24";
;
LOCATION"C2431"
$SEC"1"
CDS_SEC"1"
MATERIAL"X6S"
TOLERANCE"20%"
VALUE"22UF"
PART_NUMBER"CH622KMEB02"
VOLTAGE"4V"
PACK_TYPE"C0402"
CDS_LIB"pure_quanta";
"B"
$PN"2"9;
"A"
$PN"1"8;
%"Q_CAP"
"1","(2200,1075)","0","pure_quanta","I25";
;
LOCATION"C3916"
$SEC"1"
CDS_SEC"1"
MATERIAL"X6S"
TOLERANCE"20%"
VALUE"22UF"
PART_NUMBER"CH622KMEB02"
VOLTAGE"4V"
PACK_TYPE"C0402"
CDS_LIB"pure_quanta";
"B"
$PN"2"1;
"A"
$PN"1"4;
%"Q_CAP"
"1","(2200,1800)","0","pure_quanta","I26";
;
LOCATION"C2441"
$SEC"1"
CDS_SEC"1"
MATERIAL"X6S"
TOLERANCE"20%"
VALUE"22UF"
PART_NUMBER"CH622KMEB02"
VOLTAGE"4V"
PACK_TYPE"C0402"
CDS_LIB"pure_quanta";
"B"
$PN"2"3;
"A"
$PN"1"2;
%"Q_CAP"
"1","(2650,1075)","0","pure_quanta","I27";
;
LOCATION"C3917"
$SEC"1"
CDS_SEC"1"
MATERIAL"X6S"
TOLERANCE"20%"
VALUE"22UF"
PART_NUMBER"CH622KMEB02"
VOLTAGE"4V"
PACK_TYPE"C0402"
CDS_LIB"pure_quanta";
"B"
$PN"2"1;
"A"
$PN"1"4;
%"Q_CAP"
"1","(2650,1800)","0","pure_quanta","I28";
;
LOCATION"C2448"
$SEC"1"
CDS_SEC"1"
MATERIAL"X6S"
TOLERANCE"20%"
VALUE"22UF"
PART_NUMBER"CH622KMEB02"
VOLTAGE"4V"
PACK_TYPE"C0402"
CDS_LIB"pure_quanta";
"B"
$PN"2"3;
"A"
$PN"1"2;
%"Q_CAP"
"1","(3100,1800)","0","pure_quanta","I29";
;
LOCATION"C2455"
$SEC"1"
CDS_SEC"1"
MATERIAL"X6S"
TOLERANCE"20%"
VALUE"22UF"
PART_NUMBER"CH622KMEB02"
VOLTAGE"4V"
PACK_TYPE"C0402"
CDS_LIB"pure_quanta";
"B"
$PN"2"3;
"A"
$PN"1"2;
%"Q_CAP"
"1","(400,1800)","0","pure_quanta","I3";
;
LOCATION"C2413"
$SEC"1"
CDS_SEC"1"
MATERIAL"X6S"
TOLERANCE"20%"
VALUE"22UF"
PART_NUMBER"CH622KMEB02"
VOLTAGE"4V"
PACK_TYPE"C0402"
CDS_LIB"pure_quanta";
"B"
$PN"2"3;
"A"
$PN"1"2;
%"Q_CAP"
"1","(3100,1075)","0","pure_quanta","I30";
;
LOCATION"C3918"
$SEC"1"
CDS_SEC"1"
MATERIAL"X6S"
TOLERANCE"20%"
VALUE"22UF"
PART_NUMBER"CH622KMEB02"
VOLTAGE"4V"
PACK_TYPE"C0402"
CDS_LIB"pure_quanta";
"B"
$PN"2"1;
"A"
$PN"1"4;
%"UNIVERSAL_GND"
"1","(3100,700)","0","pure_quanta_power","I31";
;
CDS_LIB"pure_quanta_power"
HDL_POWER"GND";
"A"1;
%"Q_CAP"
"1","(3550,1800)","0","pure_quanta","I32";
;
LOCATION"C2462"
$SEC"1"
CDS_SEC"1"
MATERIAL"X6S"
TOLERANCE"20%"
VALUE"22UF"
PART_NUMBER"CH622KMEB02"
VOLTAGE"4V"
PACK_TYPE"C0402"
CDS_LIB"pure_quanta";
"B"
$PN"2"3;
"A"
$PN"1"2;
%"Q_CAP"
"1","(4000,1800)","0","pure_quanta","I33";
;
LOCATION"C2469"
$SEC"1"
CDS_SEC"1"
MATERIAL"X6S"
TOLERANCE"20%"
VALUE"22UF"
PART_NUMBER"CH622KMEB02"
VOLTAGE"4V"
PACK_TYPE"C0402"
CDS_LIB"pure_quanta";
"B"
$PN"2"3;
"A"
$PN"1"2;
%"Q_CAP"
"1","(2200,2475)","0","pure_quanta","I34";
;
LOCATION"C2440"
$SEC"1"
CDS_SEC"1"
MATERIAL"X6S"
TOLERANCE"20%"
VALUE"22UF"
PART_NUMBER"CH622KMEB02"
VOLTAGE"4V"
PACK_TYPE"C0402"
CDS_LIB"pure_quanta";
"B"
$PN"2"7;
"A"
$PN"1"6;
%"Q_CAP"
"1","(2650,2475)","0","pure_quanta","I35";
;
LOCATION"C2447"
$SEC"1"
CDS_SEC"1"
MATERIAL"X6S"
TOLERANCE"20%"
VALUE"22UF"
PART_NUMBER"CH622KMEB02"
VOLTAGE"4V"
PACK_TYPE"C0402"
CDS_LIB"pure_quanta";
"B"
$PN"2"7;
"A"
$PN"1"6;
%"Q_CAP"
"1","(2200,3150)","0","pure_quanta","I36";
;
LOCATION"C2439"
$SEC"1"
CDS_SEC"1"
MATERIAL"X6S"
TOLERANCE"20%"
VALUE"22UF"
PART_NUMBER"CH622KMEB02"
VOLTAGE"4V"
PACK_TYPE"C0402"
CDS_LIB"pure_quanta";
"B"
$PN"2"5;
"A"
$PN"1"10;
%"Q_CAP"
"1","(2200,3850)","0","pure_quanta","I37";
;
LOCATION"C2438"
$SEC"1"
CDS_SEC"1"
MATERIAL"X6S"
TOLERANCE"20%"
VALUE"22UF"
PART_NUMBER"CH622KMEB02"
VOLTAGE"4V"
PACK_TYPE"C0402"
CDS_LIB"pure_quanta";
"B"
$PN"2"9;
"A"
$PN"1"8;
%"Q_CAP"
"1","(2650,3150)","0","pure_quanta","I38";
;
LOCATION"C2446"
$SEC"1"
CDS_SEC"1"
MATERIAL"X6S"
TOLERANCE"20%"
VALUE"22UF"
PART_NUMBER"CH622KMEB02"
VOLTAGE"4V"
PACK_TYPE"C0402"
CDS_LIB"pure_quanta";
"B"
$PN"2"5;
"A"
$PN"1"10;
%"Q_CAP"
"1","(2650,3850)","0","pure_quanta","I39";
;
LOCATION"C2445"
$SEC"1"
CDS_SEC"1"
MATERIAL"X6S"
TOLERANCE"20%"
VALUE"22UF"
PART_NUMBER"CH622KMEB02"
VOLTAGE"4V"
PACK_TYPE"C0402"
CDS_LIB"pure_quanta";
"B"
$PN"2"9;
"A"
$PN"1"8;
%"Q_CAP"
"1","(850,1075)","0","pure_quanta","I4";
;
LOCATION"C3913"
$SEC"1"
CDS_SEC"1"
MATERIAL"X6S"
TOLERANCE"20%"
VALUE"22UF"
PART_NUMBER"CH622KMEB02"
VOLTAGE"4V"
PACK_TYPE"C0402"
CDS_LIB"pure_quanta";
"B"
$PN"2"1;
"A"
$PN"1"4;
%"Q_CAP"
"1","(3100,3850)","0","pure_quanta","I40";
;
LOCATION"C2452"
$SEC"1"
CDS_SEC"1"
MATERIAL"X6S"
TOLERANCE"20%"
VALUE"22UF"
PART_NUMBER"CH622KMEB02"
VOLTAGE"4V"
PACK_TYPE"C0402"
CDS_LIB"pure_quanta";
"B"
$PN"2"9;
"A"
$PN"1"8;
%"Q_CAP"
"1","(3100,3150)","0","pure_quanta","I41";
;
LOCATION"C2453"
$SEC"1"
CDS_SEC"1"
MATERIAL"X6S"
TOLERANCE"20%"
VALUE"22UF"
PART_NUMBER"CH622KMEB02"
VOLTAGE"4V"
PACK_TYPE"C0402"
CDS_LIB"pure_quanta";
"B"
$PN"2"5;
"A"
$PN"1"10;
%"Q_CAP"
"1","(3100,2475)","0","pure_quanta","I42";
;
LOCATION"C2454"
$SEC"1"
CDS_SEC"1"
MATERIAL"X6S"
TOLERANCE"20%"
VALUE"22UF"
PART_NUMBER"CH622KMEB02"
VOLTAGE"4V"
PACK_TYPE"C0402"
CDS_LIB"pure_quanta";
"B"
$PN"2"7;
"A"
$PN"1"6;
%"Q_CAP"
"1","(3550,2475)","0","pure_quanta","I43";
;
LOCATION"C2461"
$SEC"1"
CDS_SEC"1"
MATERIAL"X6S"
TOLERANCE"20%"
VALUE"22UF"
PART_NUMBER"CH622KMEB02"
VOLTAGE"4V"
PACK_TYPE"C0402"
CDS_LIB"pure_quanta";
"B"
$PN"2"7;
"A"
$PN"1"6;
%"Q_CAP"
"1","(4000,2475)","0","pure_quanta","I44";
;
LOCATION"C2468"
$SEC"1"
CDS_SEC"1"
MATERIAL"X6S"
TOLERANCE"20%"
VALUE"22UF"
PART_NUMBER"CH622KMEB02"
VOLTAGE"4V"
PACK_TYPE"C0402"
CDS_LIB"pure_quanta";
"B"
$PN"2"7;
"A"
$PN"1"6;
%"Q_CAP"
"1","(3550,3150)","0","pure_quanta","I45";
;
LOCATION"C2460"
$SEC"1"
CDS_SEC"1"
MATERIAL"X6S"
TOLERANCE"20%"
VALUE"22UF"
PART_NUMBER"CH622KMEB02"
VOLTAGE"4V"
PACK_TYPE"C0402"
CDS_LIB"pure_quanta";
"B"
$PN"2"5;
"A"
$PN"1"10;
%"Q_CAP"
"1","(3550,3850)","0","pure_quanta","I46";
;
LOCATION"C2459"
$SEC"1"
CDS_SEC"1"
MATERIAL"X6S"
TOLERANCE"20%"
VALUE"22UF"
PART_NUMBER"CH622KMEB02"
VOLTAGE"4V"
PACK_TYPE"C0402"
CDS_LIB"pure_quanta";
"B"
$PN"2"9;
"A"
$PN"1"8;
%"Q_CAP"
"1","(4000,3150)","0","pure_quanta","I47";
;
LOCATION"C2467"
$SEC"1"
CDS_SEC"1"
MATERIAL"X6S"
TOLERANCE"20%"
VALUE"22UF"
PART_NUMBER"CH622KMEB02"
VOLTAGE"4V"
PACK_TYPE"C0402"
CDS_LIB"pure_quanta";
"B"
$PN"2"5;
"A"
$PN"1"10;
%"Q_CAP"
"1","(4000,3850)","0","pure_quanta","I48";
;
LOCATION"C2466"
$SEC"1"
CDS_SEC"1"
MATERIAL"X6S"
TOLERANCE"20%"
VALUE"22UF"
PART_NUMBER"CH622KMEB02"
VOLTAGE"4V"
PACK_TYPE"C0402"
CDS_LIB"pure_quanta";
"B"
$PN"2"9;
"A"
$PN"1"8;
%"UNIVERSAL_POWER"
"1","(400,4125)","0","pure_quanta_power","I49";
;
HDL_POWER"PVDDCR_SOC_P1"
CDS_LIB"pure_quanta_power";
"A"8;
%"Q_CAP"
"1","(850,1800)","0","pure_quanta","I5";
;
LOCATION"C2420"
$SEC"1"
CDS_SEC"1"
MATERIAL"X6S"
TOLERANCE"20%"
VALUE"22UF"
PART_NUMBER"CH622KMEB02"
VOLTAGE"4V"
PACK_TYPE"C0402"
CDS_LIB"pure_quanta";
"B"
$PN"2"3;
"A"
$PN"1"2;
%"Q_CAP"
"1","(400,4550)","0","pure_quanta","I50";
;
LOCATION"C2409"
$SEC"1"
CDS_SEC"1"
MATERIAL"X6S"
TOLERANCE"20%"
VALUE"22UF"
PART_NUMBER"CH622KMEB02"
VOLTAGE"4V"
PACK_TYPE"C0402"
CDS_LIB"pure_quanta";
"B"
$PN"2"12;
"A"
$PN"1"11;
%"UNIVERSAL_POWER"
"1","(400,4825)","0","pure_quanta_power","I51";
;
HDL_POWER"PVDDCR_SOC_P1"
CDS_LIB"pure_quanta_power";
"A"11;
%"Q_CAP"
"1","(850,4550)","0","pure_quanta","I52";
;
LOCATION"C2416"
$SEC"1"
CDS_SEC"1"
MATERIAL"X6S"
TOLERANCE"20%"
VALUE"22UF"
PART_NUMBER"CH622KMEB02"
VOLTAGE"4V"
PACK_TYPE"C0402"
CDS_LIB"pure_quanta";
"B"
$PN"2"12;
"A"
$PN"1"11;
%"Q_CAP"
"1","(400,5225)","0","pure_quanta","I53";
;
LOCATION"C2408"
$SEC"1"
CDS_SEC"1"
MATERIAL"X6S"
TOLERANCE"20%"
VALUE"22UF"
PART_NUMBER"CH622KMEB02"
VOLTAGE"4V"
PACK_TYPE"C0402"
CDS_LIB"pure_quanta";
"B"
$PN"2"13;
"A"
$PN"1"16;
%"UNIVERSAL_POWER"
"1","(400,5500)","0","pure_quanta_power","I54";
;
HDL_POWER"PVDDCR_SOC_P1"
CDS_LIB"pure_quanta_power";
"A"16;
%"Q_CAP"
"1","(400,5875)","0","pure_quanta","I55";
;
LOCATION"C2407"
$SEC"1"
CDS_SEC"1"
MATERIAL"X6S"
TOLERANCE"20%"
VALUE"22UF"
PART_NUMBER"CH622KMEB02"
VOLTAGE"4V"
PACK_TYPE"C0402"
CDS_LIB"pure_quanta";
"B"
$PN"2"15;
"A"
$PN"1"14;
%"Q_CAP"
"1","(850,5225)","0","pure_quanta","I56";
;
LOCATION"C2415"
$SEC"1"
CDS_SEC"1"
MATERIAL"X6S"
TOLERANCE"20%"
VALUE"22UF"
PART_NUMBER"CH622KMEB02"
VOLTAGE"4V"
PACK_TYPE"C0402"
CDS_LIB"pure_quanta";
"B"
$PN"2"13;
"A"
$PN"1"16;
%"Q_CAP"
"1","(850,5875)","0","pure_quanta","I57";
;
LOCATION"C2414"
$SEC"1"
CDS_SEC"1"
MATERIAL"X6S"
TOLERANCE"20%"
VALUE"22UF"
PART_NUMBER"CH622KMEB02"
VOLTAGE"4V"
PACK_TYPE"C0402"
CDS_LIB"pure_quanta";
"B"
$PN"2"15;
"A"
$PN"1"14;
%"Q_CAP"
"1","(1300,4550)","0","pure_quanta","I58";
;
LOCATION"C2423"
$SEC"1"
CDS_SEC"1"
MATERIAL"X6S"
TOLERANCE"20%"
VALUE"22UF"
PART_NUMBER"CH622KMEB02"
VOLTAGE"4V"
PACK_TYPE"C0402"
CDS_LIB"pure_quanta";
"B"
$PN"2"12;
"A"
$PN"1"11;
%"Q_CAP"
"1","(1750,4550)","0","pure_quanta","I59";
;
LOCATION"C2430"
$SEC"1"
CDS_SEC"1"
MATERIAL"X6S"
TOLERANCE"20%"
VALUE"22UF"
PART_NUMBER"CH622KMEB02"
VOLTAGE"4V"
PACK_TYPE"C0402"
CDS_LIB"pure_quanta";
"B"
$PN"2"12;
"A"
$PN"1"11;
%"Q_CAP"
"1","(1300,1075)","0","pure_quanta","I6";
;
LOCATION"C3914"
$SEC"1"
CDS_SEC"1"
MATERIAL"X6S"
TOLERANCE"20%"
VALUE"22UF"
PART_NUMBER"CH622KMEB02"
VOLTAGE"4V"
PACK_TYPE"C0402"
CDS_LIB"pure_quanta";
"B"
$PN"2"1;
"A"
$PN"1"4;
%"Q_CAP"
"1","(1300,5225)","0","pure_quanta","I60";
;
LOCATION"C2422"
$SEC"1"
CDS_SEC"1"
MATERIAL"X6S"
TOLERANCE"20%"
VALUE"22UF"
PART_NUMBER"CH622KMEB02"
VOLTAGE"4V"
PACK_TYPE"C0402"
CDS_LIB"pure_quanta";
"B"
$PN"2"13;
"A"
$PN"1"16;
%"Q_CAP"
"1","(1300,5875)","0","pure_quanta","I61";
;
LOCATION"C2421"
$SEC"1"
CDS_SEC"1"
MATERIAL"X6S"
TOLERANCE"20%"
VALUE"22UF"
PART_NUMBER"CH622KMEB02"
VOLTAGE"4V"
PACK_TYPE"C0402"
CDS_LIB"pure_quanta";
"B"
$PN"2"15;
"A"
$PN"1"14;
%"Q_CAP"
"1","(1750,5225)","0","pure_quanta","I62";
;
LOCATION"C2429"
$SEC"1"
CDS_SEC"1"
MATERIAL"X6S"
TOLERANCE"20%"
VALUE"22UF"
PART_NUMBER"CH622KMEB02"
VOLTAGE"4V"
PACK_TYPE"C0402"
CDS_LIB"pure_quanta";
"B"
$PN"2"13;
"A"
$PN"1"16;
%"UNIVERSAL_POWER"
"1","(400,6150)","0","pure_quanta_power","I63";
;
HDL_POWER"PVDDCR_SOC_P1"
CDS_LIB"pure_quanta_power";
"A"14;
%"Q_CAP"
"1","(2200,4550)","0","pure_quanta","I64";
;
LOCATION"C2437"
$SEC"1"
CDS_SEC"1"
MATERIAL"X6S"
TOLERANCE"20%"
VALUE"22UF"
PART_NUMBER"CH622KMEB02"
VOLTAGE"4V"
PACK_TYPE"C0402"
CDS_LIB"pure_quanta";
"B"
$PN"2"12;
"A"
$PN"1"11;
%"Q_CAP"
"1","(2650,4550)","0","pure_quanta","I65";
;
LOCATION"C2444"
$SEC"1"
CDS_SEC"1"
MATERIAL"X6S"
TOLERANCE"20%"
VALUE"22UF"
PART_NUMBER"CH622KMEB02"
VOLTAGE"4V"
PACK_TYPE"C0402"
CDS_LIB"pure_quanta";
"B"
$PN"2"12;
"A"
$PN"1"11;
%"Q_CAP"
"1","(2200,5225)","0","pure_quanta","I66";
;
LOCATION"C2436"
$SEC"1"
CDS_SEC"1"
MATERIAL"X6S"
TOLERANCE"20%"
VALUE"22UF"
PART_NUMBER"CH622KMEB02"
VOLTAGE"4V"
PACK_TYPE"C0402"
CDS_LIB"pure_quanta";
"B"
$PN"2"13;
"A"
$PN"1"16;
%"Q_CAP"
"1","(2650,5225)","0","pure_quanta","I67";
;
LOCATION"C2443"
$SEC"1"
CDS_SEC"1"
MATERIAL"X6S"
TOLERANCE"20%"
VALUE"22UF"
PART_NUMBER"CH622KMEB02"
VOLTAGE"4V"
PACK_TYPE"C0402"
CDS_LIB"pure_quanta";
"B"
$PN"2"13;
"A"
$PN"1"16;
%"Q_CAP"
"1","(3100,5875)","0","pure_quanta","I68";
;
LOCATION"C2449"
$SEC"1"
CDS_SEC"1"
MATERIAL"X6S"
TOLERANCE"20%"
VALUE"22UF"
PART_NUMBER"CH622KMEB02"
VOLTAGE"4V"
PACK_TYPE"C0402"
CDS_LIB"pure_quanta";
"B"
$PN"2"15;
"A"
$PN"1"14;
%"Q_CAP"
"1","(3100,5225)","0","pure_quanta","I69";
;
LOCATION"C2450"
$SEC"1"
CDS_SEC"1"
MATERIAL"X6S"
TOLERANCE"20%"
VALUE"22UF"
PART_NUMBER"CH622KMEB02"
VOLTAGE"4V"
PACK_TYPE"C0402"
CDS_LIB"pure_quanta";
"B"
$PN"2"13;
"A"
$PN"1"16;
%"Q_CAP"
"1","(1300,1800)","0","pure_quanta","I7";
;
LOCATION"C2427"
$SEC"1"
CDS_SEC"1"
MATERIAL"X6S"
TOLERANCE"20%"
VALUE"22UF"
PART_NUMBER"CH622KMEB02"
VOLTAGE"4V"
PACK_TYPE"C0402"
CDS_LIB"pure_quanta";
"B"
$PN"2"3;
"A"
$PN"1"2;
%"Q_CAP"
"1","(3100,4550)","0","pure_quanta","I70";
;
LOCATION"C2451"
$SEC"1"
CDS_SEC"1"
MATERIAL"X6S"
TOLERANCE"20%"
VALUE"22UF"
PART_NUMBER"CH622KMEB02"
VOLTAGE"4V"
PACK_TYPE"C0402"
CDS_LIB"pure_quanta";
"B"
$PN"2"12;
"A"
$PN"1"11;
%"Q_CAP"
"1","(3550,4550)","0","pure_quanta","I71";
;
LOCATION"C2458"
$SEC"1"
CDS_SEC"1"
MATERIAL"X6S"
TOLERANCE"20%"
VALUE"22UF"
PART_NUMBER"CH622KMEB02"
VOLTAGE"4V"
PACK_TYPE"C0402"
CDS_LIB"pure_quanta";
"B"
$PN"2"12;
"A"
$PN"1"11;
%"Q_CAP"
"1","(4000,4550)","0","pure_quanta","I72";
;
LOCATION"C2465"
$SEC"1"
CDS_SEC"1"
MATERIAL"X6S"
TOLERANCE"20%"
VALUE"22UF"
PART_NUMBER"CH622KMEB02"
VOLTAGE"4V"
PACK_TYPE"C0402"
CDS_LIB"pure_quanta";
"B"
$PN"2"12;
"A"
$PN"1"11;
%"Q_CAP"
"1","(3550,5225)","0","pure_quanta","I73";
;
LOCATION"C2457"
$SEC"1"
CDS_SEC"1"
MATERIAL"X6S"
TOLERANCE"20%"
VALUE"22UF"
PART_NUMBER"CH622KMEB02"
VOLTAGE"4V"
PACK_TYPE"C0402"
CDS_LIB"pure_quanta";
"B"
$PN"2"13;
"A"
$PN"1"16;
%"Q_CAP"
"1","(3550,5875)","0","pure_quanta","I74";
;
LOCATION"C2456"
$SEC"1"
CDS_SEC"1"
MATERIAL"X6S"
TOLERANCE"20%"
VALUE"22UF"
PART_NUMBER"CH622KMEB02"
VOLTAGE"4V"
PACK_TYPE"C0402"
CDS_LIB"pure_quanta";
"B"
$PN"2"15;
"A"
$PN"1"14;
%"Q_CAP"
"1","(4000,5225)","0","pure_quanta","I75";
;
LOCATION"C2464"
$SEC"1"
CDS_SEC"1"
MATERIAL"X6S"
TOLERANCE"20%"
VALUE"22UF"
PART_NUMBER"CH622KMEB02"
VOLTAGE"4V"
PACK_TYPE"C0402"
CDS_LIB"pure_quanta";
"B"
$PN"2"13;
"A"
$PN"1"16;
%"Q_CAP"
"1","(4000,5875)","0","pure_quanta","I76";
;
LOCATION"C2463"
$SEC"1"
CDS_SEC"1"
MATERIAL"X6S"
TOLERANCE"20%"
VALUE"22UF"
PART_NUMBER"CH622KMEB02"
VOLTAGE"4V"
PACK_TYPE"C0402"
CDS_LIB"pure_quanta";
"B"
$PN"2"15;
"A"
$PN"1"14;
%"Q_CAP"
"1","(5000,775)","0","pure_quanta","I77";
;
LOCATION"C3919"
$SEC"1"
CDS_SEC"1"
MATERIAL"X6S"
TOLERANCE"20%"
VALUE"22UF"
PART_NUMBER"CH622KMEB02"
VOLTAGE"4V"
PACK_TYPE"C0402"
CDS_LIB"pure_quanta";
"B"
$PN"2"21;
"A"
$PN"1"20;
%"UNIVERSAL_GND"
"1","(4400,1425)","0","pure_quanta_power","I78";
;
CDS_LIB"pure_quanta_power"
HDL_POWER"GND";
"A"3;
%"Q_CAP"
"1","(4400,1800)","0","pure_quanta","I79";
;
LOCATION"C2476"
$SEC"1"
CDS_SEC"1"
MATERIAL"X6S"
TOLERANCE"20%"
VALUE"22UF"
PART_NUMBER"CH622KMEB02"
VOLTAGE"4V"
PACK_TYPE"C0402"
CDS_LIB"pure_quanta";
"B"
$PN"2"3;
"A"
$PN"1"2;
%"Q_CAP"
"1","(1750,1075)","0","pure_quanta","I8";
;
LOCATION"C3915"
$SEC"1"
CDS_SEC"1"
MATERIAL"X6S"
TOLERANCE"20%"
VALUE"22UF"
PART_NUMBER"CH622KMEB02"
VOLTAGE"4V"
PACK_TYPE"C0402"
CDS_LIB"pure_quanta";
"B"
$PN"2"1;
"A"
$PN"1"4;
%"UNIVERSAL_POWER"
"1","(5000,1050)","0","pure_quanta_power","I80";
;
HDL_POWER"PVDD11_S3_P1"
CDS_LIB"pure_quanta_power";
"A"20;
%"Q_CAP"
"1","(5000,1375)","0","pure_quanta","I81";
;
LOCATION"C2483"
$SEC"1"
CDS_SEC"1"
MATERIAL"X6S"
TOLERANCE"20%"
VALUE"22UF"
PART_NUMBER"CH622KMEB02"
VOLTAGE"4V"
PACK_TYPE"C0402"
CDS_LIB"pure_quanta";
"B"
$PN"2"19;
"A"
$PN"1"18;
%"UNIVERSAL_POWER"
"1","(5000,1650)","0","pure_quanta_power","I82";
;
HDL_POWER"PVDD11_S3_P1"
CDS_LIB"pure_quanta_power";
"A"18;
%"UNIVERSAL_GND"
"1","(5450,450)","0","pure_quanta_power","I83";
;
CDS_LIB"pure_quanta_power"
HDL_POWER"GND";
"A"21;
%"Q_CAP"
"1","(5450,775)","0","pure_quanta","I84";
;
LOCATION"C3920"
$SEC"1"
CDS_SEC"1"
MATERIAL"X6S"
TOLERANCE"20%"
VALUE"22UF"
PART_NUMBER"CH622KMEB02"
VOLTAGE"4V"
PACK_TYPE"C0402"
CDS_LIB"pure_quanta";
"B"
$PN"2"21;
"A"
$PN"1"20;
%"Q_CAP"
"1","(5450,1375)","0","pure_quanta","I85";
;
LOCATION"C2488"
$SEC"1"
CDS_SEC"1"
MATERIAL"X6S"
TOLERANCE"20%"
VALUE"22UF"
PART_NUMBER"CH622KMEB02"
VOLTAGE"4V"
PACK_TYPE"C0402"
CDS_LIB"pure_quanta";
"B"
$PN"2"19;
"A"
$PN"1"18;
%"Q_CAP"
"1","(5900,1375)","0","pure_quanta","I86";
;
LOCATION"C2492"
$SEC"1"
CDS_SEC"1"
MATERIAL"X6S"
TOLERANCE"20%"
VALUE"22UF"
PART_NUMBER"CH622KMEB02"
VOLTAGE"4V"
PACK_TYPE"C0402"
CDS_LIB"pure_quanta";
"B"
$PN"2"19;
"A"
$PN"1"18;
%"UNIVERSAL_GND"
"1","(4400,2100)","0","pure_quanta_power","I87";
;
CDS_LIB"pure_quanta_power"
HDL_POWER"GND";
"A"7;
%"Q_CAP"
"1","(4400,2475)","0","pure_quanta","I88";
;
LOCATION"C2475"
$SEC"1"
CDS_SEC"1"
MATERIAL"X6S"
TOLERANCE"20%"
VALUE"22UF"
PART_NUMBER"CH622KMEB02"
VOLTAGE"4V"
PACK_TYPE"C0402"
CDS_LIB"pure_quanta";
"B"
$PN"2"7;
"A"
$PN"1"6;
%"UNIVERSAL_GND"
"1","(4400,2775)","0","pure_quanta_power","I89";
;
CDS_LIB"pure_quanta_power"
HDL_POWER"GND";
"A"5;
%"Q_CAP"
"1","(1750,1800)","0","pure_quanta","I9";
;
LOCATION"C2434"
$SEC"1"
CDS_SEC"1"
MATERIAL"X6S"
TOLERANCE"20%"
VALUE"22UF"
PART_NUMBER"CH622KMEB02"
VOLTAGE"4V"
PACK_TYPE"C0402"
CDS_LIB"pure_quanta";
"B"
$PN"2"3;
"A"
$PN"1"2;
%"Q_CAP"
"1","(5000,2025)","0","pure_quanta","I90";
;
LOCATION"C2482"
$SEC"1"
CDS_SEC"1"
MATERIAL"X6S"
TOLERANCE"20%"
VALUE"22UF"
PART_NUMBER"CH622KMEB02"
VOLTAGE"4V"
PACK_TYPE"C0402"
CDS_LIB"pure_quanta";
"B"
$PN"2"17;
"A"
$PN"1"26;
%"UNIVERSAL_POWER"
"1","(5000,2300)","0","pure_quanta_power","I91";
;
HDL_POWER"PVDD11_S3_P1"
CDS_LIB"pure_quanta_power";
"A"26;
%"Q_CAP"
"1","(5000,2650)","0","pure_quanta","I92";
;
LOCATION"C2481"
$SEC"1"
CDS_SEC"1"
MATERIAL"X6S"
TOLERANCE"20%"
VALUE"22UF"
PART_NUMBER"CH622KMEB02"
VOLTAGE"4V"
PACK_TYPE"C0402"
CDS_LIB"pure_quanta";
"B"
$PN"2"25;
"A"
$PN"1"24;
%"UNIVERSAL_POWER"
"1","(5000,2925)","0","pure_quanta_power","I93";
;
HDL_POWER"PVDD11_S3_P1"
CDS_LIB"pure_quanta_power";
"A"24;
%"Q_CAP"
"1","(4400,3150)","0","pure_quanta","I94";
;
LOCATION"C2474"
$SEC"1"
CDS_SEC"1"
MATERIAL"X6S"
TOLERANCE"20%"
VALUE"22UF"
PART_NUMBER"CH622KMEB02"
VOLTAGE"4V"
PACK_TYPE"C0402"
CDS_LIB"pure_quanta";
"B"
$PN"2"5;
"A"
$PN"1"10;
%"UNIVERSAL_GND"
"1","(4400,3475)","0","pure_quanta_power","I95";
;
CDS_LIB"pure_quanta_power"
HDL_POWER"GND";
"A"9;
%"Q_CAP"
"1","(4400,3850)","0","pure_quanta","I96";
;
LOCATION"C2473"
$SEC"1"
CDS_SEC"1"
MATERIAL"X6S"
TOLERANCE"20%"
VALUE"22UF"
PART_NUMBER"CH622KMEB02"
VOLTAGE"4V"
PACK_TYPE"C0402"
CDS_LIB"pure_quanta";
"B"
$PN"2"9;
"A"
$PN"1"8;
%"Q_CAP"
"1","(5000,3325)","0","pure_quanta","I97";
;
LOCATION"C2480"
$SEC"1"
CDS_SEC"1"
MATERIAL"X6S"
TOLERANCE"20%"
VALUE"22UF"
PART_NUMBER"CH622KMEB02"
VOLTAGE"4V"
PACK_TYPE"C0402"
CDS_LIB"pure_quanta";
"B"
$PN"2"23;
"A"
$PN"1"22;
%"UNIVERSAL_POWER"
"1","(5000,3600)","0","pure_quanta_power","I98";
;
HDL_POWER"PVDD11_S3_P1"
CDS_LIB"pure_quanta_power";
"A"22;
%"Q_CAP"
"1","(5450,2025)","0","pure_quanta","I99";
;
LOCATION"C2487"
$SEC"1"
CDS_SEC"1"
MATERIAL"X6S"
TOLERANCE"20%"
VALUE"22UF"
PART_NUMBER"CH622KMEB02"
VOLTAGE"4V"
PACK_TYPE"C0402"
CDS_LIB"pure_quanta";
"B"
$PN"2"17;
"A"
$PN"1"26;
END.
